# SCM (Grand Teton) — schematic netlist excerpt (pin names and nets, part order shuffled) for the footprints in the layout excerpt that follows; sources: Cadence DE-HDL packaged netlist, KiCad conversion of 12092022_DA0F0TMDCD0_F0T_Management_Board_D_brd_V3_OCP.brd

PC210  Q_CAP  0.1UF 25V 10% X7R  pkg 0402  page 51 : A = SW_P5V_AUX_FLT ; B = GND
C223  Q_CAP  4700P 25V 10% EMPTY  pkg C0402  page 22 : A = RST_BMC_SRST_BUF_R_N ; B = GND
PC226  Q_CAP  22UF 10V 20% X6S  pkg C0805  page 52 : A = P3V3_AUX ; B = GND

(kicad_pcb
	(version 20260206)
	(generator "pcbnew")
	(generator_version "10.0")
	(general
		(thickness 1.6)
		(legacy_teardrops no)
	)
	(paper "A4")
	(title_block
		(title "12092022_DA0F0TMDCD0_F0T_Management_Board_D_brd_V3_OCP.brd")
		(comment 1 "Grand Teton / footprints 273-275 of 1440")
	)
	(layers
		(0 "F.Cu" signal "TOP")
		(4 "In1.Cu" signal "GND")
		(6 "In2.Cu" signal "IN1")
		(8 "In3.Cu" signal "GND1")
		(10 "In4.Cu" signal "IN2")
		(12 "In5.Cu" signal "VCC")
		(14 "In6.Cu" signal "VCC1")
		(16 "In7.Cu" signal "IN3")
		(18 "In8.Cu" signal "GND2")
		(20 "In9.Cu" signal "IN4")
		(22 "In10.Cu" signal "GND3")
		(2 "B.Cu" signal "BOTTOM")
		(9 "F.Adhes" user "F.Adhesive")
		(11 "B.Adhes" user "B.Adhesive")
		(13 "F.Paste" user "Package Geometry/Pastemask Top")
		(15 "B.Paste" user "Package Geometry/Pastemask Bottom")
		(5 "F.SilkS" user "Ref Des/Silkscreen Top")
		(7 "B.SilkS" user "Ref Des/Silkscreen Bottom")
		(1 "F.Mask" user "Board Geometry/Soldermask Top")
		(3 "B.Mask" user "Board Geometry/Soldermask Bottom")
		(17 "Dwgs.User" user "User.Drawings")
		(19 "Cmts.User" user "User.Comments")
		(21 "Eco1.User" user "User.Eco1")
		(23 "Eco2.User" user "User.Eco2")
		(25 "Edge.Cuts" user "Board Geometry/Outline")
		(27 "Margin" user)
		(31 "F.CrtYd" user "Package Geometry/Place Bound Top")
		(29 "B.CrtYd" user "Package Geometry/Place Bound Bottom")
		(35 "F.Fab" user "Ref Des/Assembly Top")
		(33 "B.Fab" user "Ref Des/Assembly Bottom")
	)
	(footprint ""
		(layer "F.Cu")
		(at 7.98322 -46.798738)
		(property "Reference" "PC210"
			(at 0 0 0)
			(layer "F.SilkS")
			(hide yes)
			(effects
				(font
					(size 1.27 1.27)
				)
			)
		)
		(property "Value" ""
			(at 0 0 0)
			(layer "F.Fab")
			(effects
				(font
					(size 1.27 1.27)
				)
			)
		)
		(duplicate_pad_numbers_are_jumpers no)
		(fp_line
			(start -0.7874 -0.4064)
			(end 0.7874 -0.4064)
			(stroke
				(width 0.1524)
				(type default)
			)
			(layer "F.SilkS")
		)
		(fp_line
			(start -0.7874 0.4064)
			(end -0.7874 -0.4064)
			(stroke
				(width 0.1524)
				(type default)
			)
			(layer "F.SilkS")
		)
		(fp_line
			(start 0.7874 -0.4064)
			(end 0.7874 0.4064)
			(stroke
				(width 0.1524)
				(type default)
			)
			(layer "F.SilkS")
		)
		(fp_line
			(start 0.7874 0.4064)
			(end -0.7874 0.4064)
			(stroke
				(width 0.1524)
				(type default)
			)
			(layer "F.SilkS")
		)
		(fp_line
			(start -0.67945 -0.305054)
			(end -0.12065 -0.305054)
			(stroke
				(width 0.1)
				(type default)
			)
			(layer "F.Fab")
		)
		(fp_line
			(start -0.67945 0.3048)
			(end -0.67945 -0.305054)
			(stroke
				(width 0.1)
				(type default)
			)
			(layer "F.Fab")
		)
		(fp_line
			(start -0.12065 -0.305054)
			(end -0.12065 -0.2794)
			(stroke
				(width 0.1)
				(type default)
			)
			(layer "F.Fab")
		)
		(fp_line
			(start -0.12065 -0.2794)
			(end 0.12065 -0.2794)
			(stroke
				(width 0.1)
				(type default)
			)
			(layer "F.Fab")
		)
		(fp_line
			(start -0.12065 0.2794)
			(end -0.12065 0.3048)
			(stroke
				(width 0.1)
				(type default)
			)
			(layer "F.Fab")
		)
		(fp_line
			(start -0.12065 0.3048)
			(end -0.67945 0.3048)
			(stroke
				(width 0.1)
				(type default)
			)
			(layer "F.Fab")
		)
		(fp_line
			(start 0.120396 0.2794)
			(end -0.12065 0.2794)
			(stroke
				(width 0.1)
				(type default)
			)
			(layer "F.Fab")
		)
		(fp_line
			(start 0.120396 0.3048)
			(end 0.120396 0.2794)
			(stroke
				(width 0.1)
				(type default)
			)
			(layer "F.Fab")
		)
		(fp_line
			(start 0.12065 -0.3048)
			(end 0.67945 -0.3048)
			(stroke
				(width 0.1)
				(type default)
			)
			(layer "F.Fab")
		)
		(fp_line
			(start 0.12065 -0.2794)
			(end 0.12065 -0.3048)
			(stroke
				(width 0.1)
				(type default)
			)
			(layer "F.Fab")
		)
		(fp_line
			(start 0.67945 -0.3048)
			(end 0.67945 0.3048)
			(stroke
				(width 0.1)
				(type default)
			)
			(layer "F.Fab")
		)
		(fp_line
			(start 0.67945 0.3048)
			(end 0.120396 0.3048)
			(stroke
				(width 0.1)
				(type default)
			)
			(layer "F.Fab")
		)
		(pad "1" smd circle
			(at -0.40005 0)
			(size 0 0)
			(layers "F.Cu" "F.Mask" "F.Paste")
			(net "SW_P5V_AUX_FLT")
		)
		(pad "2" smd circle
			(at 0.40005 0)
			(size 0 0)
			(layers "F.Cu" "F.Mask" "F.Paste")
			(net "GND")
		)
	)
	(footprint ""
		(layer "F.Cu")
		(at 4.581398 -78.196186 90)
		(property "Reference" "PC226"
			(at 0 0 90)
			(layer "F.SilkS")
			(hide yes)
			(effects
				(font
					(size 1.27 1.27)
				)
			)
		)
		(property "Value" ""
			(at 0 0 90)
			(layer "F.Fab")
			(effects
				(font
					(size 1.27 1.27)
				)
			)
		)
		(duplicate_pad_numbers_are_jumpers no)
		(fp_line
			(start 1.651 -0.8382)
			(end 1.651 0.8382)
			(stroke
				(width 0.1524)
				(type default)
			)
			(layer "F.SilkS")
		)
		(fp_line
			(start -1.651 -0.8382)
			(end 1.651 -0.8382)
			(stroke
				(width 0.1524)
				(type default)
			)
			(layer "F.SilkS")
		)
		(fp_line
			(start 1.651 0.8382)
			(end -1.651 0.8382)
			(stroke
				(width 0.1524)
				(type default)
			)
			(layer "F.SilkS")
		)
		(fp_line
			(start 0 0.8382)
			(end 0 -0.8382)
			(stroke
				(width 0.1524)
				(type default)
			)
			(layer "F.SilkS")
		)
		(fp_line
			(start -1.651 0.8382)
			(end -1.651 -0.8382)
			(stroke
				(width 0.1524)
				(type default)
			)
			(layer "F.SilkS")
		)
		(fp_line
			(start 1.55956 -0.7366)
			(end 1.524 -0.7366)
			(stroke
				(width 0.1)
				(type default)
			)
			(layer "F.Fab")
		)
		(fp_line
			(start 1.524 -0.7366)
			(end -1.524 -0.7366)
			(stroke
				(width 0.1)
				(type default)
			)
			(layer "F.Fab")
		)
		(fp_line
			(start -1.524 -0.7366)
			(end -1.55956 -0.7366)
			(stroke
				(width 0.1)
				(type default)
			)
			(layer "F.Fab")
		)
		(fp_line
			(start -1.55956 -0.7366)
			(end -1.55956 0.7366)
			(stroke
				(width 0.1)
				(type default)
			)
			(layer "F.Fab")
		)
		(fp_line
			(start 1.55956 0.7366)
			(end 1.55956 -0.7366)
			(stroke
				(width 0.1)
				(type default)
			)
			(layer "F.Fab")
		)
		(fp_line
			(start 1.524 0.7366)
			(end 1.55956 0.7366)
			(stroke
				(width 0.1)
				(type default)
			)
			(layer "F.Fab")
		)
		(fp_line
			(start -1.524 0.7366)
			(end 1.524 0.7366)
			(stroke
				(width 0.1)
				(type default)
			)
			(layer "F.Fab")
		)
		(fp_line
			(start -1.55956 0.7366)
			(end -1.524 0.7366)
			(stroke
				(width 0.1)
				(type default)
			)
			(layer "F.Fab")
		)
		(pad "1" smd rect
			(at -0.94996 0 270)
			(size 1.1176 1.3716)
			(layers "F.Cu" "F.Mask" "F.Paste")
			(net "P3V3_AUX")
		)
		(pad "2" smd rect
			(at 0.94996 0 270)
			(size 1.1176 1.3716)
			(layers "F.Cu" "F.Mask" "F.Paste")
			(net "GND")
		)
	)
	(footprint ""
		(layer "F.Cu")
		(at 10.033 -89.408)
		(property "Reference" "C223"
			(at 0 0 0)
			(layer "F.SilkS")
			(hide yes)
			(effects
				(font
					(size 1.27 1.27)
				)
			)
		)
		(property "Value" ""
			(at 0 0 0)
			(layer "F.Fab")
			(effects
				(font
					(size 1.27 1.27)
				)
			)
		)
		(duplicate_pad_numbers_are_jumpers no)
		(fp_line
			(start -0.7874 -0.4064)
			(end 0.7874 -0.4064)
			(stroke
				(width 0.1524)
				(type default)
			)
			(layer "F.SilkS")
		)
		(fp_line
			(start -0.7874 0.4064)
			(end -0.7874 -0.4064)
			(stroke
				(width 0.1524)
				(type default)
			)
			(layer "F.SilkS")
		)
		(fp_line
			(start 0.7874 -0.4064)
			(end 0.7874 0.4064)
			(stroke
				(width 0.1524)
				(type default)
			)
			(layer "F.SilkS")
		)
		(fp_line
			(start 0.7874 0.4064)
			(end -0.7874 0.4064)
			(stroke
				(width 0.1524)
				(type default)
			)
			(layer "F.SilkS")
		)
		(fp_line
			(start -0.67945 -0.305054)
			(end -0.12065 -0.305054)
			(stroke
				(width 0.1)
				(type default)
			)
			(layer "F.Fab")
		)
		(fp_line
			(start -0.67945 0.3048)
			(end -0.67945 -0.305054)
			(stroke
				(width 0.1)
				(type default)
			)
			(layer "F.Fab")
		)
		(fp_line
			(start -0.12065 -0.305054)
			(end -0.12065 -0.2794)
			(stroke
				(width 0.1)
				(type default)
			)
			(layer "F.Fab")
		)
		(fp_line
			(start -0.12065 -0.2794)
			(end 0.12065 -0.2794)
			(stroke
				(width 0.1)
				(type default)
			)
			(layer "F.Fab")
		)
		(fp_line
			(start -0.12065 0.2794)
			(end -0.12065 0.3048)
			(stroke
				(width 0.1)
				(type default)
			)
			(layer "F.Fab")
		)
		(fp_line
			(start -0.12065 0.3048)
			(end -0.67945 0.3048)
			(stroke
				(width 0.1)
				(type default)
			)
			(layer "F.Fab")
		)
		(fp_line
			(start 0.120396 0.2794)
			(end -0.12065 0.2794)
			(stroke
				(width 0.1)
				(type default)
			)
			(layer "F.Fab")
		)
		(fp_line
			(start 0.120396 0.3048)
			(end 0.120396 0.2794)
			(stroke
				(width 0.1)
				(type default)
			)
			(layer "F.Fab")
		)
		(fp_line
			(start 0.12065 -0.3048)
			(end 0.67945 -0.3048)
			(stroke
				(width 0.1)
				(type default)
			)
			(layer "F.Fab")
		)
		(fp_line
			(start 0.12065 -0.2794)
			(end 0.12065 -0.3048)
			(stroke
				(width 0.1)
				(type default)
			)
			(layer "F.Fab")
		)
		(fp_line
			(start 0.67945 -0.3048)
			(end 0.67945 0.3048)
			(stroke
				(width 0.1)
				(type default)
			)
			(layer "F.Fab")
		)
		(fp_line
			(start 0.67945 0.3048)
			(end 0.120396 0.3048)
			(stroke
				(width 0.1)
				(type default)
			)
			(layer "F.Fab")
		)
		(pad "1" smd circle
			(at -0.40005 0)
			(size 0 0)
			(layers "F.Cu" "F.Mask" "F.Paste")
			(net "RST_BMC_SRST_BUF_R_N")
		)
		(pad "2" smd circle
			(at 0.40005 0)
			(size 0 0)
			(layers "F.Cu" "F.Mask" "F.Paste")
			(net "GND")
		)
	)
)
